FILE_TYPE = CONNECTIVITY;
{Allegro Design Entry HDL 16.6-p007 (v16-6-112F) 10/10/2012}
"PAGE_NUMBER" = 212;
0"NC";
1"GND\g";
2"GND\g";
3"GND\g";
4"GND\g";
5"GND\g";
6"GND\g";
7"GND\g";
8"GND\g";
9"GND\g";
10"GND\g";
11"GND\g";
12"GND\g";
13"GND\g";
14"PVCCIO_CPU0\g";
15"GND\g";
16"GND\g";
17"GND\g";
18"P12V_STBY\g";
19"P5V_STBY\g";
20"GND\g";
21"PVCCIO_CPU0\g";
22"VR_FET_SW_P12V_STBY_PVCCIO_CPU0\g";
23"VR_FET_SW_P12V_STBY_PVCCIO_CPU0\g"VOLTAGE"12";
24"PVCCIO_CPU0\g";
25"VSENSE_PVCCIO_CPU0_AVSP";
26"VR_PVCCIO_CPU0_OCSET";
27"ISENSE_PVCCIO_CPU0_PH1_IMON";
28"A_TSENSE_PVCCIO_CPU0";
29"VR_PVCCIO_CPU0_AIREF1";
30"VR_PVCCIO_CPU0_PWM1";
31"VR_PVCCIO_CPU0_PH1_BOOT_R";
32"TP_PVCCIO_CPU0_GL_0";
33"TP_PVCCIO_CPU0_GL_1";
34"VR_PVCCIO_CPU0_PH1_VCIN"VOLTAGE"5";
35"VR_PVCCIO_CPU0_PH1_PHASE"VOLTAGE"5";
36"VR_PVCCIO_CPU0_PH1_SW"VOLTAGE"5";
37"VR_PVCCIO_CPU0_PH1_SW_RC";
38"VSENSE_PVCCIO_CPU0_SKT_VRTN";
39"VSENSE_PVCCIO_CPU0_SKT_VSEN";
40"VSENSE_PVCCIO_CPU0_AVSN";
41"VR_PVCCIO_CPU0_PH1_BOOT";
%"IR354XX"
"1","(1250,3950)","0","mstr_discrete","I101";
;
PART_NUMBER"H73684-001"
MATERIAL"IC"
LOCATION"EU7C1"
CDS_LIB"mstr_discrete"
CDS_LOCATION"EU7C1"
CDS_SEC"1"
$SEC"1"
PACK_TYPE"SM"
VALUE"IR35412";
"TOUT_FLT"
$PN"36"28;
"NC"
$PN"31"0;
"OCSET"
$PN"37"26;
"IOUT"
$PN"38"27;
"SW"
$PN"10"36;
"BOOST"
$PN"33"31;
"REFIN"
$PN"39"29;
"PWM"
$PN"34"30;
"PHASE"
$PN"32"35;
"VIN<0>"
$PN"25"22;
"VCC"
$PN"3"34;
"VIN<1>"
$PN"30"22;
"EN"
$PN"35"19;
"VDRV"
$PN"4"19;
"VOS"
$PN"1"14;
"LGND"
$PN"2"16;
"PGND<1>"
$PN"7"16;
"PGND<2>"
$PN"40"16;
"PGND<0>"
$PN"5"16;
"GL<0>"
$PN"6"32;
"GL<1>"
$PN"41"33;
%"GND"
"1","(3525,3950)","0","mstr_symbols","I102";
;
VOLTAGE"0"
CDS_LIB"mstr_symbols"
SIZE"1B"
BOM_COST"PROC_VRD_VCCIN_CPU0"
ROOM"PVSA_CPU1_PWR_VR"
BODY_TYPE"PLUMBING"
HDL_POWER"GND";
"A\NAC"1;
%"RES"
"2","(3525,4125)","0","mstr_discrete","I103";
;
CDS_LOCATION"R7C25"
VALUE"68.1K"
TOLERANCE"1%"
LOCATION"R7C25"
WATTAGE"1/16W"
MATERIAL"EMPTY"
PART_NUMBER"G21796-187"
PACK_TYPE"0402"
CDS_LIB"mstr_discrete"
CDS_SEC"1"
$SEC"1";
"A"
$PN"1"26;
"B"
$PN"2"1;
%"SHUNT"
"1","(-1300,1850)","0","mstr_misc","I104";
;
CDS_SEC"1"
CDS_LOCATION"SH3P1"
PART_NUMBER"N_A"
LOCATION"SH3P1"
SEC_TYPE"SH0201"
SEC"1"
CDS_LIB"mstr_misc"
PIN_SHORT"A:B"
PACK_TYPE"SH0201"
MATERIAL"EMPTY";
"A"
$PN"1"39;
"B"
$PN"2"25;
%"SHUNT"
"1","(-1300,1400)","0","mstr_misc","I105";
;
CDS_SEC"1"
CDS_LOCATION"SH3P2"
LOCATION"SH3P2"
PART_NUMBER"N_A"
SEC_TYPE"SH0201"
SEC"1"
CDS_LIB"mstr_misc"
MATERIAL"EMPTY"
PACK_TYPE"SH0201"
PIN_SHORT"A:B";
"A"
$PN"1"38;
"B"
$PN"2"40;
%"CAP_A"
"1","(450,3450)","0","dev_discrete","I106";
;
CDS_SEC"1"
$SEC"1"
CDS_LOCATION"CT70"
POP"NOPOP"
VALUE"0.1UF"
VOLTAGE"16V"
LOCATION"CT70"
TOLERANCE"10%"
MATERIAL"X7R"
PART_NUMBER"A36096-030"
PACK_TYPE"0402V"
ROOM"PVCCIN_CPU0_PWR_VR"
CDS_LIB"dev_discrete";
"B"
$PN"2"2;
"A"
$PN"1"29;
%"GND"
"1","(450,3200)","0","mstr_symbols","I107";
;
ROOM"PVCCIN_CPU0_PWR_VR"
BOM_COST"PROC_VRD_VCCIN_CPU0"
SIZE"1B"
VOLTAGE"0"
CDS_LIB"mstr_symbols"
BODY_TYPE"PLUMBING"
HDL_POWER"GND";
"A\NAC"2;
%"CAP"
"1","(2375,3975)","0","mstr_discrete","I109";
;
CDS_SEC"1"
$SEC"1"
CDS_LOCATION"CT71"
VALUE"1000PF"
LOCATION"CT71"
VOLTAGE"50V"
TOLERANCE"10%"
PACK_TYPE"0402LF"
POP"NOPOP"
PART_NUMBER"A36096-046"
MATERIAL"X7R"
ROOM"VDDQ_KLM_PWR_VR"
CDS_LIB"mstr_discrete";
"A"
$PN"1"28;
"B"
$PN"2"3;
%"GND"
"1","(2375,3750)","0","mstr_symbols","I110";
;
ROOM"VDDQ_KLM_PWR_VR"
VOLTAGE"0"
SIZE"1B"
CDS_LIB"mstr_symbols"
BODY_TYPE"PLUMBING"
HDL_POWER"GND";
"A\NAC"3;
%"GND"
"1","(2625,2900)","0","mstr_symbols","I113";
;
ROOM"PVCCIN_CPU0_PWR_VR"
BOM_COST"PROC_VRD_VCCIN_CPU0"
VOLTAGE"0"
SIZE"1B"
CDS_LIB"mstr_symbols"
BODY_TYPE"PLUMBING"
HDL_POWER"GND";
"A\NAC"4;
%"CAP"
"1","(2625,3450)","0","mstr_discrete","I118";
;
CDS_SEC"1"
CDS_LOCATION"CT72"
LOCATION"CT72"
POP"NOPOP"
PACK_TYPE"0402LF"
PART_NUMBER"A36096-046"
MATERIAL"X7R"
TOLERANCE"10%"
VOLTAGE"50V"
VALUE"1000PF"
SEC_TYPE"0402LF"
SEC"1"
ROOM"VDDQ_KLM_PWR_VR"
CDS_LIB"mstr_discrete";
"A"
$PN"1"36;
"B"
$PN"2"37;
%"RES"
"1","(-475,3750)","0","mstr_discrete","I120";
;
CDS_SEC"1"
CDS_LOCATION"RT47"
LOCATION"RT47"
PACK_TYPE"0603"
VALUE"0"
TOLERANCE"5.0%"
MATERIAL"CHIP"
PART_NUMBER"G22178-002"
WATTAGE"1/10W"
SEC_TYPE"0603"
SEC"1"
BOM_COST"NT_GBE_BASE"
ROOM"NIC_SPRV"
CDS_LIB"mstr_discrete";
"B"
$PN"2"31;
"A"
$PN"1"41;
%"SC22U16V5MX-4-GP"
"1","(2900,2175)","0","w_hdl","I124";
;
CDS_SEC"1"
CDS_LOCATION"C22W33"
LOCATION"C22W33"
PACK_SIZE"0805"
TYPE"X6S"
RATED"16V"
TOLERANCE"20%"
ATTRIBUTE"22UF"
VALUE"SC22U16V5MX-4-GP"
CDS_LMAN_SYM_OUTLINE"-50,25,50,-25"
CDS_LIB"w_hdl"
PART_NUMBER"078.22611.0811"
SEC_TYPE"SMD-BCG5"
SEC"1"
PACK_TYPE"SMD-BCG5";
"2"
$PN"2"5;
"1"
$PN"1"23;
%"GND"
"1","(2900,1950)","0","mstr_symbols","I125";
;
SIZE"1B"
VOLTAGE"0"
ROOM"PVPP_KLM_VR"
BOM_COST"PVPP_KLM_VR"
CDS_LIB"mstr_symbols"
BODY_TYPE"PLUMBING"
HDL_POWER"GND";
"A\NAC"5;
%"SC22U16V5MX-4-GP"
"1","(2600,2175)","0","w_hdl","I126";
;
CDS_SEC"1"
CDS_LOCATION"C22W32"
ATTRIBUTE"22UF"
LOCATION"C22W32"
TOLERANCE"20%"
RATED"16V"
TYPE"X6S"
PACK_SIZE"0805"
VALUE"SC22U16V5MX-4-GP"
PACK_TYPE"SMD-BCG5"
SEC"1"
SEC_TYPE"SMD-BCG5"
PART_NUMBER"078.22611.0811"
CDS_LIB"w_hdl"
CDS_LMAN_SYM_OUTLINE"-50,25,50,-25";
"2"
$PN"2"7;
"1"
$PN"1"23;
%"GND"
"1","(2300,1950)","0","mstr_symbols","I127";
;
CDS_LIB"mstr_symbols"
BOM_COST"PVPP_KLM_VR"
ROOM"PVPP_KLM_VR"
VOLTAGE"0"
SIZE"1B"
BODY_TYPE"PLUMBING"
HDL_POWER"GND";
"A\NAC"6;
%"GND"
"1","(2600,1950)","0","mstr_symbols","I128";
;
SIZE"1B"
VOLTAGE"0"
ROOM"PVPP_KLM_VR"
BOM_COST"PVPP_KLM_VR"
CDS_LIB"mstr_symbols"
BODY_TYPE"PLUMBING"
HDL_POWER"GND";
"A\NAC"7;
%"SC22U16V5MX-4-GP"
"1","(2300,2175)","0","w_hdl","I129";
;
CDS_SEC"1"
CDS_LOCATION"C22W31"
ATTRIBUTE"22UF"
TOLERANCE"20%"
RATED"16V"
TYPE"X6S"
PACK_SIZE"0805"
VALUE"SC22U16V5MX-4-GP"
LOCATION"C22W31"
PACK_TYPE"SMD-BCG5"
SEC"1"
SEC_TYPE"SMD-BCG5"
PART_NUMBER"078.22611.0811"
CDS_LIB"w_hdl"
CDS_LMAN_SYM_OUTLINE"-50,25,50,-25";
"2"
$PN"2"6;
"1"
$PN"1"23;
%"GND"
"1","(850,950)","0","mstr_symbols","I13";
;
SIZE"1B"
BOM_COST"PROC_VRD_PVCCIO_CPU0"
ROOM"PVCCIO_CPU0"
VOLTAGE"0"
CDS_LIB"mstr_symbols"
BODY_TYPE"PLUMBING"
HDL_POWER"GND";
"A\NAC"8;
%"SC22U16V5MX-4-GP"
"1","(2000,2175)","0","w_hdl","I130";
;
CDS_SEC"1"
CDS_LOCATION"C7C8"
LOCATION"C7C8"
ATTRIBUTE"22UF"
TOLERANCE"20%"
RATED"16V"
TYPE"X6S"
PACK_SIZE"0805"
VALUE"SC22U16V5MX-4-GP"
CDS_LMAN_SYM_OUTLINE"-50,25,50,-25"
CDS_LIB"w_hdl"
PART_NUMBER"078.22611.0811"
SEC_TYPE"SMD-BCG5"
SEC"1"
PACK_TYPE"SMD-BCG5";
"2"
$PN"2"9;
"1"
$PN"1"23;
%"GND"
"1","(2000,1950)","0","mstr_symbols","I131";
;
CDS_LIB"mstr_symbols"
BOM_COST"PVPP_KLM_VR"
ROOM"PVPP_KLM_VR"
VOLTAGE"0"
SIZE"1B"
BODY_TYPE"PLUMBING"
HDL_POWER"GND";
"A\NAC"9;
%"SC22U16V5MX-4-GP"
"1","(1550,2175)","0","w_hdl","I132";
;
CDS_SEC"1"
CDS_LOCATION"C22W30"
LOCATION"C22W30"
ATTRIBUTE"22UF"
TOLERANCE"20%"
TYPE"X6S"
PACK_SIZE"0805"
VALUE"SC22U16V5MX-4-GP"
RATED"16V"
CDS_LMAN_SYM_OUTLINE"-50,25,50,-25"
CDS_LIB"w_hdl"
PART_NUMBER"078.22611.0811"
SEC_TYPE"SMD-BCG5"
SEC"1"
PACK_TYPE"SMD-BCG5";
"2"
$PN"2"10;
"1"
$PN"1"23;
%"GND"
"1","(1550,1950)","0","mstr_symbols","I133";
;
CDS_LIB"mstr_symbols"
BOM_COST"PVPP_KLM_VR"
ROOM"PVPP_KLM_VR"
VOLTAGE"0"
SIZE"1B"
BODY_TYPE"PLUMBING"
HDL_POWER"GND";
"A\NAC"10;
%"SC22U16V5MX-4-GP"
"1","(1250,2175)","0","w_hdl","I134";
;
CDS_SEC"1"
CDS_LOCATION"C22W29"
ATTRIBUTE"22UF"
TOLERANCE"20%"
RATED"16V"
PACK_SIZE"0805"
TYPE"X6S"
LOCATION"C22W29"
VALUE"SC22U16V5MX-4-GP"
CDS_LMAN_SYM_OUTLINE"-50,25,50,-25"
CDS_LIB"w_hdl"
PART_NUMBER"078.22611.0811"
SEC_TYPE"SMD-BCG5"
SEC"1"
PACK_TYPE"SMD-BCG5";
"2"
$PN"2"11;
"1"
$PN"1"23;
%"GND"
"1","(1250,1950)","0","mstr_symbols","I135";
;
SIZE"1B"
VOLTAGE"0"
ROOM"PVPP_KLM_VR"
BOM_COST"PVPP_KLM_VR"
CDS_LIB"mstr_symbols"
BODY_TYPE"PLUMBING"
HDL_POWER"GND";
"A\NAC"11;
%"SC22U16V5MX-4-GP"
"1","(950,2175)","0","w_hdl","I136";
;
CDS_SEC"1"
CDS_LOCATION"C22W28"
LOCATION"C22W28"
ATTRIBUTE"22UF"
TOLERANCE"20%"
PACK_SIZE"0805"
RATED"16V"
TYPE"X6S"
VALUE"SC22U16V5MX-4-GP"
CDS_LMAN_SYM_OUTLINE"-50,25,50,-25"
CDS_LIB"w_hdl"
PART_NUMBER"078.22611.0811"
SEC_TYPE"SMD-BCG5"
SEC"1"
PACK_TYPE"SMD-BCG5";
"2"
$PN"2"12;
"1"
$PN"1"23;
%"GND"
"1","(950,1950)","0","mstr_symbols","I137";
;
SIZE"1B"
VOLTAGE"0"
ROOM"PVPP_KLM_VR"
BOM_COST"PVPP_KLM_VR"
CDS_LIB"mstr_symbols"
BODY_TYPE"PLUMBING"
HDL_POWER"GND";
"A\NAC"12;
%"SC22U16V5MX-4-GP"
"1","(650,2175)","0","w_hdl","I138";
;
CDS_SEC"1"
CDS_LOCATION"C7C7"
LOCATION"C7C7"
ATTRIBUTE"22UF"
TOLERANCE"20%"
RATED"16V"
TYPE"X6S"
PACK_SIZE"0805"
VALUE"SC22U16V5MX-4-GP"
PACK_TYPE"SMD-BCG5"
SEC"1"
SEC_TYPE"SMD-BCG5"
PART_NUMBER"078.22611.0811"
CDS_LIB"w_hdl"
CDS_LMAN_SYM_OUTLINE"-50,25,50,-25";
"2"
$PN"2"13;
"1"
$PN"1"23;
%"GND"
"1","(650,1950)","0","mstr_symbols","I139";
;
CDS_LIB"mstr_symbols"
BOM_COST"PVPP_KLM_VR"
ROOM"PVPP_KLM_VR"
VOLTAGE"0"
SIZE"1B"
BODY_TYPE"PLUMBING"
HDL_POWER"GND";
"A\NAC"13;
%"RES"
"1","(-1200,4750)","0","mstr_discrete","I140";
;
PACK_TYPE"0402"
TOLERANCE"5%"
PART_NUMBER"G21497-005"
VALUE"0.0"
LOCATION"R3N7"
MATERIAL"CHIP"
WATTAGE"1/16W"
BOM_COST"PROC_SIDEBAND"
CDS_LIB"mstr_discrete"
SEC_TYPE"0402"
SEC"1"
ROOM"CPU0"
CDS_SEC"1"
CDS_LOCATION"R3N7";
"B"
$PN"2"19;
"A"
$PN"1"34;
%"IND-150NH-56-GP"
"1","(3075,3675)","1","w_hdl","I141";
;
CDS_SEC"1"
CDS_LOCATION"L7C2"
VALUE"IND-150NH-56-GP"
ATTRIBUTE"150NH"
RATED"ISAT=75A@25C"
TYPE"IRMS=66A@DELTA_T<40C"
PACK_SIZE"DCR=0.17MOHM"
LOCATION"L7C2"
PART_NUMBER"068.1512N.M001"
CDS_LIB"w_hdl"
CDS_LMAN_SYM_OUTLINE"-75,100,75,-100"
SEC_TYPE"DISCRET-GA1"
SEC"1"
PACK_TYPE"DISCRET-GA1";
"F"
$PN"2"14;
"S"
$PN"1"36;
%"IND-100NH-35-GP"
"1","(225,2475)","1","w_hdl","I142";
;
CDS_SEC"1"
CDS_LOCATION"L7C1"
RATED"ISAT=16A@25C"
PACK_SIZE"DCR=0.16MOHM"
TYPE"IRMS=29A@DELTA_T<45C"
LOCATION"L7C1"
ATTRIBUTE"100NH"
VALUE"IND-100NH-35-GP"
CDS_LMAN_SYM_OUTLINE"-75,100,75,-100"
CDS_LIB"w_hdl"
PART_NUMBER"068.1011N.M001"
SEC_TYPE"DISCRET-G8"
SEC"1"
PACK_TYPE"DISCRET-G8";
"F"
$PN"2"23;
"S"
$PN"1"18;
%"SC1U10V2KX-4-GP"
"1","(-825,4200)","0","w_hdl","I143";
;
CDS_SEC"1"
CDS_LOCATION"C7C20"
LOCATION"C7C20"
ATTRIBUTE"1UF"
TOLERANCE"10%"
RATED"10V"
PACK_SIZE"0402"
VALUE"SC1U10V2KX-4-GP"
CDS_LMAN_SYM_OUTLINE"-50,25,50,-25"
CDS_LIB"w_hdl"
PART_NUMBER"78.10523.8FL"
SEC_TYPE"SMD-BCG6"
SEC"1"
PACK_TYPE"SMD-BCG6";
"2"
$PN"2"17;
"1"
$PN"1"19;
%"1R3F-GP"
"1","(2625,3100)","0","w_hdl","I144";
;
CDS_SEC"1"
CDS_LOCATION"RT48"
PACK_SIZE"0603"
LOCATION"RT48"
POP"NOPOP"
VALUE"1R3F-GP"
RATED"1/10W"
TOLERANCE"1%"
ATTRIBUTE"1 OHM"
PACK_TYPE"RCL_GP"
SEC"1"
SEC_TYPE"RCL_GP"
PART_NUMBER"64.1R005.55L"
CDS_LIB"w_hdl"
CDS_LMAN_SYM_OUTLINE"-50,75,50,-75";
"2"
$PN"2"4;
"1"
$PN"1"37;
%"CAPP"
"1","(1400,1300)","2","mstr_discrete","I145";
;
LOCATION"C3N26"
PACK_TYPE"3018"
VALUE"470UF"
VOLTAGE"2.5V"
MATERIAL"ALUM"
GROUP"PWR_BULK_CAP"
TOLERANCE"20%"
PART_NUMBER"699013-049"
$SEC"1"
CDS_SEC"1"
BOM_COST"PROC_VRD_PVCCIO_CPU0"
CDS_LIB"mstr_discrete"
ROOM"PVCCIO_CPU0"
CDS_LOCATION"C3N26";
"B"
$PN"2"8;
"A"
$PN"1"24;
%"CAPP"
"1","(1950,1300)","2","mstr_discrete","I146";
;
MATERIAL"ALUM"
VOLTAGE"2.5V"
TOLERANCE"20%"
VALUE"470UF"
PACK_TYPE"3018"
LOCATION"C3N38"
GROUP"PWR_BULK_CAP"
PART_NUMBER"699013-049"
ROOM"PVCCIO_CPU0"
CDS_LIB"mstr_discrete"
BOM_COST"PROC_VRD_PVCCIO_CPU0"
CDS_SEC"1"
$SEC"1"
CDS_LOCATION"C3N38";
"B"
$PN"2"8;
"A"
$PN"1"24;
%"CAPP"
"1","(850,1300)","2","mstr_discrete","I18";
;
PART_NUMBER"699013-049"
PACK_TYPE"3018"
LOCATION"C3N35"
VALUE"470UF"
TOLERANCE"20%"
VOLTAGE"2.5V"
MATERIAL"ALUM"
GROUP"PWR_BULK_CAP"
$SEC"1"
CDS_SEC"1"
BOM_COST"PROC_VRD_PVCCIO_CPU0"
CDS_LOCATION"C3N35"
CDS_LIB"mstr_discrete"
ROOM"PVCCIO_CPU0";
"B"
$PN"2"8;
"A"
$PN"1"24;
%"PVCCIO_CPU0"
"1","(4025,3775)","0","mstr_symbols","I22";
;
VOLTAGE"1.1V"
CDS_LIB"mstr_symbols"
BODY_TYPE"PLUMBING"
HDL_POWER"PVCCIO_CPU0";
"G\NAC"14;
%"CAP_A"
"1","(3350,3450)","0","dev_discrete","I23";
;
TOLERANCE"20%"
MATERIAL"X6S"
VOLTAGE"4V"
LOCATION"C7C6"
VALUE"22.0UF"
PART_NUMBER"E15431-004"
PACK_TYPE"0603V"
GROUP"PWR_MLCC_CAP"
CDS_LIB"dev_discrete"
ROOM"PVCCIO_CPU0"
SEC"1"
SEC_TYPE"0603V"
CDS_SEC"1"
BOM_COST"PROC_VRD_PVCCIO_CPU0"
CDS_LOCATION"C7C6";
"B"
$PN"2"15;
"A"
$PN"1"14;
%"GND"
"1","(4025,3025)","0","mstr_symbols","I24";
;
VOLTAGE"0.0V"
CDS_LIB"mstr_symbols"
SIZE"1B"
BOM_COST"PROC_VRD_PVCCIO_CPU0"
ROOM"PVCCIO_CPU0"
BODY_TYPE"PLUMBING"
HDL_POWER"GND";
"A\NAC"15;
%"GND"
"1","(1900,3200)","0","mstr_symbols","I29";
;
ROOM"PVCCIO_CPU0"
VOLTAGE"0.0V"
SIZE"1B"
CDS_LIB"mstr_symbols"
BOM_COST"PROC_VRD_PVCCIO_CPU0"
BODY_TYPE"PLUMBING"
HDL_POWER"GND";
"A\NAC"16;
%"CAP"
"1","(-350,4225)","0","mstr_discrete","I33";
;
CDS_SEC"1"
VOLTAGE"16V"
TOLERANCE"10%"
LOCATION"C7C18"
PACK_TYPE"0402"
PART_NUMBER"A36096-155"
MATERIAL"X7R"
VALUE"0.22UF"
SEC_TYPE"0402"
SEC"1"
CDS_LOCATION"C7C18"
ROOM"PVCCIO_CPU0"
CDS_LIB"mstr_discrete";
"A"
$PN"1"19;
"B"
$PN"2"17;
%"CAP"
"1","(-1350,4225)","0","mstr_discrete","I36";
;
CDS_SEC"1"
VALUE"1.0UF"
VOLTAGE"16V"
PACK_TYPE"0402"
TOLERANCE"10%"
MATERIAL"X6S"
PART_NUMBER"D97712-011"
LOCATION"C7C17"
CDS_LIB"mstr_discrete"
CDS_LOCATION"C7C17"
ROOM"PVCCIO_CPU0"
SEC"1"
SEC_TYPE"0402";
"A"
$PN"1"34;
"B"
$PN"2"17;
%"CAP"
"1","(-1600,3600)","2","mstr_discrete","I37";
;
CDS_SEC"1"
VALUE"0.220UF"
PART_NUMBER"A36096-104"
VOLTAGE"16V"
TOLERANCE"10%"
MATERIAL"X7R"
PACK_TYPE"0402"
LOCATION"C7C14"
SEC"1"
SEC_TYPE"0402"
SPOF"TRUE"
ROOM"PVCCIO_CPU0"
CDS_LOCATION"C7C14"
CDS_LIB"mstr_discrete";
"A"
$PN"1"41;
"B"
$PN"2"35;
%"CAP_A"
"1","(-1650,4225)","0","dev_discrete","I38";
;
VOLTAGE"16V"
PACK_TYPE"0402V"
MATERIAL"X7R"
VALUE"0.1UF"
LOCATION"C7C11"
TOLERANCE"10%"
PART_NUMBER"A36096-030"
CDS_LOCATION"C7C11"
CDS_SEC"1"
SEC_TYPE"0402V"
SEC"1"
ROOM"PVCCIO_CPU0"
CDS_LIB"dev_discrete";
"B"
$PN"2"17;
"A"
$PN"1"22;
%"CAP"
"1","(-1950,4225)","0","mstr_discrete","I39";
;
CDS_SEC"1"
LOCATION"C7C12"
PACK_TYPE"0402"
PART_NUMBER"D97712-011"
TOLERANCE"10%"
VOLTAGE"16V"
VALUE"1.0UF"
MATERIAL"X6S"
ROOM"PVCCIO_CPU0"
CDS_LOCATION"C7C12"
SEC"1"
SEC_TYPE"0402"
CDS_LIB"mstr_discrete";
"A"
$PN"1"22;
"B"
$PN"2"17;
%"CAP"
"1","(-2250,4225)","0","mstr_discrete","I40";
;
CDS_SEC"1"
LOCATION"C3N36"
VALUE"10UF"
VOLTAGE"16V"
PACK_TYPE"0805"
PART_NUMBER"C95333-007"
MATERIAL"X6S"
TOLERANCE"10%"
ROOM"PVCCIO_CPU0"
CDS_LOCATION"C3N36"
SEC"1"
SEC_TYPE"0805"
CDS_LIB"mstr_discrete";
"A"
$PN"1"22;
"B"
$PN"2"17;
%"CAP"
"1","(-2475,4225)","0","mstr_discrete","I41";
;
CDS_SEC"1"
LOCATION"C3N33"
VALUE"10UF"
TOLERANCE"10%"
PACK_TYPE"0805"
VOLTAGE"16V"
MATERIAL"X6S"
PART_NUMBER"C95333-007"
ROOM"PVCCIO_CPU0"
SEC"1"
SEC_TYPE"0805"
CDS_LOCATION"C3N33"
CDS_LIB"mstr_discrete";
"A"
$PN"1"22;
"B"
$PN"2"17;
%"CAP"
"1","(-2725,4225)","0","mstr_discrete","I43";
;
CDS_SEC"1"
VALUE"10UF"
VOLTAGE"16V"
MATERIAL"X6S"
PART_NUMBER"C95333-007"
TOLERANCE"10%"
PACK_TYPE"0805"
LOCATION"C3N34"
SEC_TYPE"0805"
SEC"1"
ROOM"PVCCIO_CPU0"
CDS_LOCATION"C3N34"
CDS_LIB"mstr_discrete";
"A"
$PN"1"22;
"B"
$PN"2"17;
%"GND"
"1","(-2725,3850)","0","mstr_symbols","I44";
;
ROOM"PVCCIO_CPU0"
BOM_COST"PROC_VRD_PVCCIO_CPU0"
VOLTAGE"0.0V"
CDS_LIB"mstr_symbols"
SIZE"1B"
BODY_TYPE"PLUMBING"
HDL_POWER"GND";
"A\NAC"17;
%"P12V_STBY"
"1","(-50,2550)","0","mstr_symbols","I57";
;
VOLTAGE"12.0V"
CDS_LIB"mstr_symbols"
SIZE"1B"
BODY_TYPE"PLUMBING"
HDL_POWER"P12V_STBY";
"G\NAC"18;
%"P5V_STBY"
"1","(0,4875)","0","mstr_symbols","I58";
;
VOLTAGE"5.0V"
CDS_LIB"mstr_symbols"
SIZE"1B"
BODY_TYPE"PLUMBING"
HDL_POWER"P5V_STBY";
"G\NAC"19;
%"CAP_A"
"1","(-1925,1675)","0","dev_discrete","I60";
;
CDS_SEC"1"
LOCATION"C3P1"
VALUE"0.1UF"
VOLTAGE"16V"
TOLERANCE"10%"
MATERIAL"EMPTY"
PART_NUMBER"A36096-030"
PACK_TYPE"0402V"
SEC_TYPE"0402V"
SEC"1"
ROOM"PVCCIO_CPU0"
BOM_COST"PROC_VRD_PVCCIO_CPU0"
CDS_LOCATION"C3P1"
CDS_LIB"dev_discrete";
"B"
$PN"2"38;
"A"
$PN"1"39;
%"RES"
"1","(-725,1150)","0","mstr_discrete","I68";
;
CDS_SEC"1"
PACK_TYPE"0402"
MATERIAL"CHIP"
LOCATION"R3N20"
TOLERANCE"1%"
VALUE"100.0"
WATTAGE"1/16W"
PART_NUMBER"G21796-017"
SEC_TYPE"0402"
SEC"1"
CDS_LIB"mstr_discrete"
ROOM"PVCCIO_CPU0"
BOM_COST"PROC_VRD_PVCCIO_CPU0"
CDS_LOCATION"R3N20";
"B"
$PN"2"20;
"A"
$PN"1"40;
%"GND"
"1","(-450,925)","0","mstr_symbols","I69";
;
ROOM"PVCCIO_CPU0"
BOM_COST"MEM_VRD_PVCCIO_CPU0"
CDS_LIB"mstr_symbols"
SIZE"1B"
VOLTAGE"0"
BODY_TYPE"PLUMBING"
HDL_POWER"GND";
"A\NAC"20;
%"RES"
"1","(-725,2325)","0","mstr_discrete","I74";
;
CDS_SEC"1"
LOCATION"R3N21"
TOLERANCE"1%"
VALUE"100.0"
PACK_TYPE"0402"
MATERIAL"CHIP"
WATTAGE"1/16W"
PART_NUMBER"G21796-017"
SEC_TYPE"0402"
SEC"1"
CDS_LIB"mstr_discrete"
LOCATION"R3N21"
ROOM"PVCCIO_CPU0"
CDS_LOCATION"R3N21"
BOM_COST"PROC_VRD_PVCCIO_CPU0"
CDS_LOCATION"R3N21";
"B"
$PN"2"21;
"A"
$PN"1"25;
%"PVCCIO_CPU0"
"1","(-500,2525)","0","mstr_symbols","I75";
;
VOLTAGE"1.1V"
CDS_LIB"mstr_symbols"
BODY_TYPE"PLUMBING"
HDL_POWER"PVCCIO_CPU0";
"G\NAC"21;
%"CAP_A"
"1","(3650,3450)","0","dev_discrete","I77";
;
LOCATION"C7C10"
VALUE"22.0UF"
VOLTAGE"4V"
TOLERANCE"20%"
PACK_TYPE"0603V"
PART_NUMBER"E15431-004"
MATERIAL"X6S"
GROUP"PWR_MLCC_CAP"
CDS_LIB"dev_discrete"
SEC"1"
SEC_TYPE"0603V"
CDS_SEC"1"
CDS_LOCATION"C7C10";
"B"
$PN"2"15;
"A"
$PN"1"14;
%"RES"
"2","(4025,3450)","0","mstr_discrete","I78";
;
CDS_SEC"1"
WATTAGE"1/16W"
MATERIAL"CHIP"
PART_NUMBER"G21796-208"
PACK_TYPE"0402"
VALUE"51.1"
TOLERANCE"1.0%"
LOCATION"R7C3"
CDS_LIB"mstr_discrete"
CDS_LOCATION"R7C3"
SEC_TYPE"0402"
SEC"1";
"A"
$PN"1"14;
"B"
$PN"2"15;
%"VCC_CORE"
"1","(-2725,4750)","0","mstr_symbols","I79";
;
HDL_POWER"VR_FET_SW_P12V_STBY_PVCCIO_CPU0"
CDS_LIB"mstr_symbols";
"A"22;
%"VCC_CORE"
"1","(2900,2650)","0","mstr_symbols","I80";
;
HDL_POWER"VR_FET_SW_P12V_STBY_PVCCIO_CPU0"
CDS_LIB"mstr_symbols";
"A"23;
%"PVCCIO_CPU0"
"1","(850,1600)","0","mstr_symbols","I82";
;
VOLTAGE"1.1V"
CDS_LIB"mstr_symbols"
BODY_TYPE"PLUMBING"
HDL_POWER"PVCCIO_CPU0";
"G\NAC"24;
END.
